(kicad_pcb
	(version 20260206)
	(generator "pcbnew")
	(generator_version "10.0")
	(general
		(thickness 1.6)
		(legacy_teardrops no)
	)
	(paper "A4")
	(title_block
		(title "pdpb — Lightning_PDPB_BRD.brd")
		(comment 1 "Lightning (Wiwynn / Facebook NVMe JBOF) / footprints 1061-1068 of 1140")
	)
	(layers
		(0 "F.Cu" signal "TOP")
		(4 "In1.Cu" signal "L2GND")
		(6 "In2.Cu" signal "L3")
		(8 "In3.Cu" signal "L4VCC")
		(10 "In4.Cu" signal "L5VCC")
		(12 "In5.Cu" signal "L6")
		(14 "In6.Cu" signal "L7GND")
		(2 "B.Cu" signal "BOTTOM")
		(9 "F.Adhes" user "F.Adhesive")
		(11 "B.Adhes" user "B.Adhesive")
		(13 "F.Paste" user "Package Geometry/Pastemask Top")
		(15 "B.Paste" user "Package Geometry/Pastemask Bottom")
		(5 "F.SilkS" user "Ref Des/Silkscreen Top")
		(7 "B.SilkS" user "Ref Des/Silkscreen Bottom")
		(1 "F.Mask" user "Board Geometry/Soldermask Top")
		(3 "B.Mask" user "Board Geometry/Soldermask Bottom")
		(17 "Dwgs.User" user "User.Drawings")
		(19 "Cmts.User" user "User.Comments")
		(21 "Eco1.User" user "User.Eco1")
		(23 "Eco2.User" user "User.Eco2")
		(25 "Edge.Cuts" user "Board Geometry/Outline")
		(27 "Margin" user)
		(31 "F.CrtYd" user "Package Geometry/Place Bound Top")
		(29 "B.CrtYd" user "Package Geometry/Place Bound Bottom")
		(35 "F.Fab" user "Ref Des/Assembly Top")
		(33 "B.Fab" user "Ref Des/Assembly Bottom")
	)
	(footprint ""
		(layer "F.Cu")
		(at 34.9504 -395.3002)
		(property "Reference" "PC1241"
			(at 0 0 0)
			(layer "F.SilkS")
			(hide yes)
			(effects
				(font
					(size 1.27 1.27)
				)
			)
		)
		(property "Value" "SC22U25V6KX-GP-U"
			(at -2.860802 -5.279644 0)
			(unlocked yes)
			(layer "F.Fab")
			(hide yes)
			(effects
				(font
					(size 1.016 1.016)
					(thickness 0.1524)
				)
			)
		)
		(property "Device Type" "C1206-TO0D3H75"
			(at -2.860802 -6.803644 0)
			(unlocked yes)
			(layer "F.Fab")
			(hide yes)
			(effects
				(font
					(size 1.016 1.016)
					(thickness 0.1524)
				)
			)
		)
		(duplicate_pad_numbers_are_jumpers no)
		(fp_line
			(start -1.3081 -2.3749)
			(end 1.3081 -2.3749)
			(stroke
				(width 0.1524)
				(type default)
			)
			(layer "F.SilkS")
		)
		(fp_line
			(start -1.3081 2.3749)
			(end -1.3081 -2.3749)
			(stroke
				(width 0.1524)
				(type default)
			)
			(layer "F.SilkS")
		)
		(fp_line
			(start 1.3081 -2.3749)
			(end 1.3081 2.3749)
			(stroke
				(width 0.1524)
				(type default)
			)
			(layer "F.SilkS")
		)
		(fp_line
			(start 1.3081 2.3749)
			(end -1.3081 2.3749)
			(stroke
				(width 0.1524)
				(type default)
			)
			(layer "F.SilkS")
		)
		(fp_rect
			(start -0.8001 1.6002)
			(end 0.8001 -1.6002)
			(stroke
				(width 0)
				(type default)
			)
			(fill no)
			(layer "F.CrtYd")
		)
		(fp_poly
			(pts
				(xy -1.5621 2.4511) (xy -1.5621 1.6002) (xy 0.8001 1.6002) (xy 0.8001 -1.6002) (xy -0.8001 -1.6002)
				(xy -0.8001 1.5875) (xy -1.5621 1.5875) (xy -1.5621 -2.4511) (xy 1.5621 -2.4511) (xy 1.5621 2.4511)
			)
			(stroke
				(width 0)
				(type default)
			)
			(fill no)
			(layer "F.CrtYd")
		)
		(fp_rect
			(start -1.5621 2.4511)
			(end 1.5621 -2.4511)
			(stroke
				(width 0)
				(type default)
			)
			(fill no)
			(layer "F.Fab")
		)
		(pad "1" smd rect
			(at 0 -1.392936)
			(size 2.1082 1.4478)
			(layers "F.Cu" "F.Mask" "F.Paste")
			(net "P12V_SSD6")
		)
		(pad "2" smd rect
			(at 0 1.392936)
			(size 2.1082 1.4478)
			(layers "F.Cu" "F.Mask" "F.Paste")
			(net "GND")
		)
	)
	(footprint ""
		(layer "F.Cu")
		(at 206.502 -295.529)
		(property "Reference" "D20"
			(at 0 0 0)
			(layer "F.SilkS")
			(hide yes)
			(effects
				(font
					(size 1.27 1.27)
				)
			)
		)
		(property "Value" "RB551V30-1-GP"
			(at 0 -6.7818 0)
			(unlocked yes)
			(layer "F.Fab")
			(hide yes)
			(effects
				(font
					(size 1.016 1.016)
					(thickness 0.1524)
				)
			)
		)
		(property "Device Type" "SOD323AKH44"
			(at 0 -8.6868 0)
			(unlocked yes)
			(layer "F.Fab")
			(hide yes)
			(effects
				(font
					(size 1.016 1.016)
					(thickness 0.1524)
				)
			)
		)
		(duplicate_pad_numbers_are_jumpers no)
		(fp_line
			(start -0.889 -1.9304)
			(end 0.889 -1.9304)
			(stroke
				(width 0.1524)
				(type default)
			)
			(layer "F.SilkS")
		)
		(fp_line
			(start -0.889 2.159)
			(end -0.889 -1.9304)
			(stroke
				(width 0.1524)
				(type default)
			)
			(layer "F.SilkS")
		)
		(fp_line
			(start 0.762 2.0574)
			(end -0.762 2.0574)
			(stroke
				(width 0.508)
				(type default)
			)
			(layer "F.SilkS")
		)
		(fp_line
			(start 0.889 -1.9304)
			(end 0.889 2.159)
			(stroke
				(width 0.1524)
				(type default)
			)
			(layer "F.SilkS")
		)
		(fp_line
			(start 0.889 2.159)
			(end -0.889 2.159)
			(stroke
				(width 0.1524)
				(type default)
			)
			(layer "F.SilkS")
		)
		(fp_rect
			(start -1.016 2.3114)
			(end 1.016 -2.0066)
			(stroke
				(width 0)
				(type default)
			)
			(fill no)
			(layer "F.CrtYd")
		)
		(fp_poly
			(pts
				(xy -1.016 -2.0066) (xy 1.016 -2.0066) (xy 1.016 2.3114) (xy -1.016 2.3114)
			)
			(stroke
				(width 0)
				(type default)
			)
			(fill no)
			(layer "F.Fab")
		)
		(pad "A" smd rect
			(at 0 -1.143)
			(size 0.5588 1.016)
			(layers "F.Cu" "F.Mask" "F.Paste")
			(net "SW_SSD2_R")
		)
		(pad "K" smd rect
			(at 0 1.143)
			(size 0.5588 1.016)
			(layers "F.Cu" "F.Mask" "F.Paste")
			(net "SW_SSD2_N")
		)
	)
	(footprint ""
		(layer "F.Cu")
		(at 70.993 -454.66 180)
		(property "Reference" "R349"
			(at 0 0 180)
			(layer "F.SilkS")
			(hide yes)
			(effects
				(font
					(size 1.27 1.27)
				)
			)
		)
		(property "Value" "4K7R2J-2-GP"
			(at 0.064008 -3.993896 180)
			(unlocked yes)
			(layer "F.Fab")
			(hide yes)
			(effects
				(font
					(size 1.016 1.016)
					(thickness 0.1524)
				)
			)
		)
		(property "Device Type" "R402H16"
			(at 0.064008 -5.517896 180)
			(unlocked yes)
			(layer "F.Fab")
			(hide yes)
			(effects
				(font
					(size 1.016 1.016)
					(thickness 0.1524)
				)
			)
		)
		(duplicate_pad_numbers_are_jumpers no)
		(fp_line
			(start 0.508 -0.9398)
			(end -0.508 -0.9398)
			(stroke
				(width 0.1524)
				(type default)
			)
			(layer "F.SilkS")
		)
		(fp_line
			(start -0.508 -0.9398)
			(end -0.508 0.9398)
			(stroke
				(width 0.1524)
				(type default)
			)
			(layer "F.SilkS")
		)
		(fp_rect
			(start -0.508 0.9398)
			(end 0.508 -0.9398)
			(stroke
				(width 0)
				(type default)
			)
			(fill no)
			(layer "F.CrtYd")
		)
		(fp_rect
			(start -0.508 0.9398)
			(end 0.508 -0.9398)
			(stroke
				(width 0)
				(type default)
			)
			(fill no)
			(layer "F.Fab")
		)
		(pad "1" smd custom
			(at 0 -0.4445 180)
			(size 0.1397 0.1397)
			(layers "F.Cu" "F.Mask" "F.Paste")
			(net "EEPROM_A1")
			(options
				(clearance outline)
				(anchor circle)
			)
			(primitives
				(gr_poly
					(pts
						(arc
							(start -0.1778 -0.2794)
							(mid -0.249642 -0.249642)
							(end -0.2794 -0.1778)
						)
						(arc
							(start -0.2794 0.1778)
							(mid -0.249642 0.249642)
							(end -0.1778 0.2794)
						)
						(arc
							(start 0.1778 0.2794)
							(mid 0.249642 0.249642)
							(end 0.2794 0.1778)
						)
						(arc
							(start 0.2794 -0.1778)
							(mid 0.249642 -0.249642)
							(end 0.1778 -0.2794)
						)
					)
					(width 0)
					(fill yes)
				)
			)
		)
		(pad "2" smd custom
			(at 0 0.4445 180)
			(size 0.1397 0.1397)
			(layers "F.Cu" "F.Mask" "F.Paste")
			(net "GND")
			(options
				(clearance outline)
				(anchor circle)
			)
			(primitives
				(gr_poly
					(pts
						(arc
							(start -0.1778 -0.2794)
							(mid -0.249642 -0.249642)
							(end -0.2794 -0.1778)
						)
						(arc
							(start -0.2794 0.1778)
							(mid -0.249642 0.249642)
							(end -0.1778 0.2794)
						)
						(arc
							(start 0.1778 0.2794)
							(mid 0.249642 0.249642)
							(end 0.2794 0.1778)
						)
						(arc
							(start 0.2794 -0.1778)
							(mid 0.249642 -0.249642)
							(end 0.1778 -0.2794)
						)
					)
					(width 0)
					(fill yes)
				)
			)
		)
	)
	(footprint ""
		(layer "F.Cu")
		(at 21.5138 -89.535)
		(property "Reference" "D27"
			(at 0 0 0)
			(layer "F.SilkS")
			(hide yes)
			(effects
				(font
					(size 1.27 1.27)
				)
			)
		)
		(property "Value" "RB551V30-1-GP"
			(at 0 -6.7818 0)
			(unlocked yes)
			(layer "F.Fab")
			(hide yes)
			(effects
				(font
					(size 1.016 1.016)
					(thickness 0.1524)
				)
			)
		)
		(property "Device Type" "SOD323AKH44"
			(at 0 -8.6868 0)
			(unlocked yes)
			(layer "F.Fab")
			(hide yes)
			(effects
				(font
					(size 1.016 1.016)
					(thickness 0.1524)
				)
			)
		)
		(duplicate_pad_numbers_are_jumpers no)
		(fp_line
			(start -0.889 -1.9304)
			(end 0.889 -1.9304)
			(stroke
				(width 0.1524)
				(type default)
			)
			(layer "F.SilkS")
		)
		(fp_line
			(start -0.889 2.159)
			(end -0.889 -1.9304)
			(stroke
				(width 0.1524)
				(type default)
			)
			(layer "F.SilkS")
		)
		(fp_line
			(start 0.762 2.0574)
			(end -0.762 2.0574)
			(stroke
				(width 0.508)
				(type default)
			)
			(layer "F.SilkS")
		)
		(fp_line
			(start 0.889 -1.9304)
			(end 0.889 2.159)
			(stroke
				(width 0.1524)
				(type default)
			)
			(layer "F.SilkS")
		)
		(fp_line
			(start 0.889 2.159)
			(end -0.889 2.159)
			(stroke
				(width 0.1524)
				(type default)
			)
			(layer "F.SilkS")
		)
		(fp_rect
			(start -1.016 2.3114)
			(end 1.016 -2.0066)
			(stroke
				(width 0)
				(type default)
			)
			(fill no)
			(layer "F.CrtYd")
		)
		(fp_poly
			(pts
				(xy -1.016 -2.0066) (xy 1.016 -2.0066) (xy 1.016 2.3114) (xy -1.016 2.3114)
			)
			(stroke
				(width 0)
				(type default)
			)
			(fill no)
			(layer "F.Fab")
		)
		(pad "A" smd rect
			(at 0 -1.143)
			(size 0.5588 1.016)
			(layers "F.Cu" "F.Mask" "F.Paste")
			(net "SW_SSD9_R")
		)
		(pad "K" smd rect
			(at 0 1.143)
			(size 0.5588 1.016)
			(layers "F.Cu" "F.Mask" "F.Paste")
			(net "SW_SSD9_N")
		)
	)
	(footprint ""
		(layer "F.Cu")
		(at 34.0868 -499.1608)
		(property "Reference" "R9245"
			(at 0 0 0)
			(layer "F.SilkS")
			(hide yes)
			(effects
				(font
					(size 1.27 1.27)
				)
			)
		)
		(property "Value" "2R2010F-GP"
			(at 0.0762 -4.5466 0)
			(unlocked yes)
			(layer "F.Fab")
			(hide yes)
			(effects
				(font
					(size 1.016 1.016)
					(thickness 0.1524)
				)
			)
		)
		(property "Device Type" "R2010H26"
			(at 0.0762 -6.1468 0)
			(unlocked yes)
			(layer "F.Fab")
			(hide yes)
			(effects
				(font
					(size 1.016 1.016)
					(thickness 0.1524)
				)
			)
		)
		(duplicate_pad_numbers_are_jumpers no)
		(fp_line
			(start -3.302 -1.651)
			(end -3.302 1.651)
			(stroke
				(width 0.1524)
				(type default)
			)
			(layer "F.SilkS")
		)
		(fp_line
			(start -3.302 1.651)
			(end 3.302 1.651)
			(stroke
				(width 0.1524)
				(type default)
			)
			(layer "F.SilkS")
		)
		(fp_line
			(start 3.302 -1.651)
			(end -3.302 -1.651)
			(stroke
				(width 0.1524)
				(type default)
			)
			(layer "F.SilkS")
		)
		(fp_line
			(start 3.302 1.651)
			(end 3.302 -1.651)
			(stroke
				(width 0.1524)
				(type default)
			)
			(layer "F.SilkS")
		)
		(fp_rect
			(start -3.3782 1.7272)
			(end 3.3782 -1.7272)
			(stroke
				(width 0)
				(type default)
			)
			(fill no)
			(layer "F.CrtYd")
		)
		(fp_poly
			(pts
				(xy 3.3782 -1.7272) (xy -3.3782 -1.7272) (xy -3.3782 1.7272) (xy 3.3782 1.7272)
			)
			(stroke
				(width 0)
				(type default)
			)
			(fill no)
			(layer "F.Fab")
		)
		(pad "1" smd rect
			(at -2.3495 0)
			(size 1.143 2.794)
			(layers "F.Cu" "F.Mask" "F.Paste")
			(net "P12V_SSD5")
		)
		(pad "2" smd rect
			(at 2.3495 0)
			(size 1.143 2.794)
			(layers "F.Cu" "F.Mask" "F.Paste")
			(net "12V_PRECH_SSD5")
		)
	)
	(footprint ""
		(layer "F.Cu")
		(at 206.502 -192.532)
		(property "Reference" "D21"
			(at 0 0 0)
			(layer "F.SilkS")
			(hide yes)
			(effects
				(font
					(size 1.27 1.27)
				)
			)
		)
		(property "Value" "RB551V30-1-GP"
			(at 0 -6.7818 0)
			(unlocked yes)
			(layer "F.Fab")
			(hide yes)
			(effects
				(font
					(size 1.016 1.016)
					(thickness 0.1524)
				)
			)
		)
		(property "Device Type" "SOD323AKH44"
			(at 0 -8.6868 0)
			(unlocked yes)
			(layer "F.Fab")
			(hide yes)
			(effects
				(font
					(size 1.016 1.016)
					(thickness 0.1524)
				)
			)
		)
		(duplicate_pad_numbers_are_jumpers no)
		(fp_line
			(start -0.889 -1.9304)
			(end 0.889 -1.9304)
			(stroke
				(width 0.1524)
				(type default)
			)
			(layer "F.SilkS")
		)
		(fp_line
			(start -0.889 2.159)
			(end -0.889 -1.9304)
			(stroke
				(width 0.1524)
				(type default)
			)
			(layer "F.SilkS")
		)
		(fp_line
			(start 0.762 2.0574)
			(end -0.762 2.0574)
			(stroke
				(width 0.508)
				(type default)
			)
			(layer "F.SilkS")
		)
		(fp_line
			(start 0.889 -1.9304)
			(end 0.889 2.159)
			(stroke
				(width 0.1524)
				(type default)
			)
			(layer "F.SilkS")
		)
		(fp_line
			(start 0.889 2.159)
			(end -0.889 2.159)
			(stroke
				(width 0.1524)
				(type default)
			)
			(layer "F.SilkS")
		)
		(fp_rect
			(start -1.016 2.3114)
			(end 1.016 -2.0066)
			(stroke
				(width 0)
				(type default)
			)
			(fill no)
			(layer "F.CrtYd")
		)
		(fp_poly
			(pts
				(xy -1.016 -2.0066) (xy 1.016 -2.0066) (xy 1.016 2.3114) (xy -1.016 2.3114)
			)
			(stroke
				(width 0)
				(type default)
			)
			(fill no)
			(layer "F.Fab")
		)
		(pad "A" smd rect
			(at 0 -1.143)
			(size 0.5588 1.016)
			(layers "F.Cu" "F.Mask" "F.Paste")
			(net "SW_SSD3_R")
		)
		(pad "K" smd rect
			(at 0 1.143)
			(size 0.5588 1.016)
			(layers "F.Cu" "F.Mask" "F.Paste")
			(net "SW_SSD3_N")
		)
	)
	(footprint ""
		(layer "F.Cu")
		(at 17.77365 -463.126074 -90)
		(property "Reference" "R9948"
			(at 0 0 270)
			(layer "F.SilkS")
			(hide yes)
			(effects
				(font
					(size 1.27 1.27)
				)
			)
		)
		(property "Value" "4K7R2J-2-GP"
			(at 0.064008 -3.993896 270)
			(unlocked yes)
			(layer "F.Fab")
			(hide yes)
			(effects
				(font
					(size 1.016 1.016)
					(thickness 0.1524)
				)
			)
		)
		(property "Device Type" "R402H16"
			(at 0.064008 -5.517896 270)
			(unlocked yes)
			(layer "F.Fab")
			(hide yes)
			(effects
				(font
					(size 1.016 1.016)
					(thickness 0.1524)
				)
			)
		)
		(duplicate_pad_numbers_are_jumpers no)
		(fp_line
			(start -0.508 -0.9398)
			(end -0.508 0.9398)
			(stroke
				(width 0.1524)
				(type default)
			)
			(layer "F.SilkS")
		)
		(fp_line
			(start 0.508 -0.9398)
			(end -0.508 -0.9398)
			(stroke
				(width 0.1524)
				(type default)
			)
			(layer "F.SilkS")
		)
		(fp_rect
			(start -0.508 0.9398)
			(end 0.508 -0.9398)
			(stroke
				(width 0)
				(type default)
			)
			(fill no)
			(layer "F.CrtYd")
		)
		(fp_rect
			(start -0.508 0.9398)
			(end 0.508 -0.9398)
			(stroke
				(width 0)
				(type default)
			)
			(fill no)
			(layer "F.Fab")
		)
		(pad "1" smd custom
			(at 0 -0.4445 270)
			(size 0.1397 0.1397)
			(layers "F.Cu" "F.Mask" "F.Paste")
			(net "P3V3")
			(options
				(clearance outline)
				(anchor circle)
			)
			(primitives
				(gr_poly
					(pts
						(arc
							(start -0.1778 -0.2794)
							(mid -0.249642 -0.249642)
							(end -0.2794 -0.1778)
						)
						(arc
							(start -0.2794 0.1778)
							(mid -0.249642 0.249642)
							(end -0.1778 0.2794)
						)
						(arc
							(start 0.1778 0.2794)
							(mid 0.249642 0.249642)
							(end 0.2794 0.1778)
						)
						(arc
							(start 0.2794 -0.1778)
							(mid 0.249642 -0.249642)
							(end 0.1778 -0.2794)
						)
					)
					(width 0)
					(fill yes)
				)
			)
		)
		(pad "2" smd custom
			(at 0 0.4445 270)
			(size 0.1397 0.1397)
			(layers "F.Cu" "F.Mask" "F.Paste")
			(net "SSD_ACT_DR10_MOS_N")
			(options
				(clearance outline)
				(anchor circle)
			)
			(primitives
				(gr_poly
					(pts
						(arc
							(start -0.1778 -0.2794)
							(mid -0.249642 -0.249642)
							(end -0.2794 -0.1778)
						)
						(arc
							(start -0.2794 0.1778)
							(mid -0.249642 0.249642)
							(end -0.1778 0.2794)
						)
						(arc
							(start 0.1778 0.2794)
							(mid 0.249642 0.249642)
							(end 0.2794 0.1778)
						)
						(arc
							(start 0.2794 -0.1778)
							(mid 0.249642 -0.249642)
							(end 0.1778 -0.2794)
						)
					)
					(width 0)
					(fill yes)
				)
			)
		)
	)
	(footprint ""
		(layer "F.Cu")
		(at 30.999938 -379.000004 -90)
		(property "Reference" "U49"
			(at 0 0 270)
			(layer "F.SilkS")
			(hide yes)
			(effects
				(font
					(size 1.27 1.27)
				)
			)
		)
		(property "Value" "TMP75AIDGKR-GP"
			(at -0.1143 -9.1948 270)
			(unlocked yes)
			(layer "F.Fab")
			(hide yes)
			(effects
				(font
					(size 1.016 1.016)
					(thickness 0.1524)
				)
			)
		)
		(property "Device Type" "MSOP8-1H44"
			(at -0.1143 -10.795 270)
			(unlocked yes)
			(layer "F.Fab")
			(hide yes)
			(effects
				(font
					(size 1.016 1.016)
					(thickness 0.1524)
				)
			)
		)
		(duplicate_pad_numbers_are_jumpers no)
		(fp_line
			(start -1.778 1.0922)
			(end -1.778 3.048)
			(stroke
				(width 0.508)
				(type default)
			)
			(layer "F.SilkS")
		)
		(fp_line
			(start -1.9558 1.016)
			(end 1.0795 1.016)
			(stroke
				(width 0.1524)
				(type default)
			)
			(layer "F.SilkS")
		)
		(fp_line
			(start 1.0795 1.016)
			(end 1.0795 -1.016)
			(stroke
				(width 0.1524)
				(type default)
			)
			(layer "F.SilkS")
		)
		(fp_line
			(start -1.4478 -0.0381)
			(end -1.9558 0.4699)
			(stroke
				(width 0.1524)
				(type default)
			)
			(layer "F.SilkS")
		)
		(fp_line
			(start -1.9558 -0.5461)
			(end -1.4478 -0.0381)
			(stroke
				(width 0.1524)
				(type default)
			)
			(layer "F.SilkS")
		)
		(fp_line
			(start -1.9558 -1.016)
			(end -1.9558 1.016)
			(stroke
				(width 0.1524)
				(type default)
			)
			(layer "F.SilkS")
		)
		(fp_line
			(start 1.0795 -1.016)
			(end -1.9558 -1.016)
			(stroke
				(width 0.1524)
				(type default)
			)
			(layer "F.SilkS")
		)
		(fp_poly
			(pts
				(xy -1.1557 -1.016) (xy -1.1557 1.016) (xy 1.1557 1.016) (xy 1.1557 -1.016)
			)
			(stroke
				(width 0)
				(type default)
			)
			(fill yes)
			(layer "F.SilkS")
		)
		(fp_rect
			(start -1.4986 2.4511)
			(end 1.4986 -2.4511)
			(stroke
				(width 0)
				(type default)
			)
			(fill no)
			(layer "F.CrtYd")
		)
		(fp_poly
			(pts
				(xy -2.032 3.302) (xy -2.032 -3.302) (xy 2.032 -3.302) (xy 2.032 -2.1209) (xy 1.4986 -2.1209) (xy 1.4986 -2.4511)
				(xy -1.4986 -2.4511) (xy -1.4986 2.4511) (xy 1.4986 2.4511) (xy 1.4986 -2.1082) (xy 2.032 -2.1082)
				(xy 2.032 3.302)
			)
			(stroke
				(width 0)
				(type default)
			)
			(fill no)
			(layer "F.CrtYd")
		)
		(fp_rect
			(start -2.032 3.302)
			(end 2.032 -3.302)
			(stroke
				(width 0)
				(type default)
			)
			(fill no)
			(layer "F.Fab")
		)
		(pad "1" smd rect
			(at -0.97536 2.05486 270)
			(size 0.3556 1.524)
			(layers "F.Cu" "F.Mask" "F.Paste")
			(net "TMP4_SDA")
		)
		(pad "2" smd rect
			(at -0.32512 2.05486 270)
			(size 0.3556 1.524)
			(layers "F.Cu" "F.Mask" "F.Paste")
			(net "TMP4_SCL")
		)
		(pad "3" smd rect
			(at 0.32512 2.05486 270)
			(size 0.3556 1.524)
			(layers "F.Cu" "F.Mask" "F.Paste")
			(net "I2C_B_TMP4_ALERT")
		)
		(pad "4" smd rect
			(at 0.97536 2.05486 270)
			(size 0.3556 1.524)
			(layers "F.Cu" "F.Mask" "F.Paste")
			(net "GND")
		)
		(pad "5" smd rect
			(at 0.97536 -2.05486 270)
			(size 0.3556 1.524)
			(layers "F.Cu" "F.Mask" "F.Paste")
			(net "I2C_B_TMP4_A2")
		)
		(pad "6" smd rect
			(at 0.32512 -2.05486 270)
			(size 0.3556 1.524)
			(layers "F.Cu" "F.Mask" "F.Paste")
			(net "I2C_B_TMP4_A1")
		)
		(pad "7" smd rect
			(at -0.32512 -2.05486 270)
			(size 0.3556 1.524)
			(layers "F.Cu" "F.Mask" "F.Paste")
			(net "I2C_B_TMP4_A0")
		)
		(pad "8" smd rect
			(at -0.97536 -2.05486 270)
			(size 0.3556 1.524)
			(layers "F.Cu" "F.Mask" "F.Paste")
			(net "P3V3")
		)
	)
)
